# S9S_MB_2U (Grand Teton) — schematic netlist excerpt (pin names and nets, part order shuffled) for the footprints in the layout excerpt that follows; sources: Cadence DE-HDL packaged netlist, KiCad conversion of 03242023_DA0F0TMBIJ0_F0T_Motherboard_J_brd_V01_OCP.brd

PC1672  Q_CAP  22UF 16V 20% X6S  pkg C0805  page 271 : A = SW_P12V_PVCCFA_EHV_FIVRA_CPU0_L ; B = GND
R1962  Q_RES  20K 1% EMPTY  pkg 0402LF  page 198 : A = FM_PCH_CONSENT_STRAP_N ; B = GND
PR574  Q_RES  100 1% CHIP  pkg 0402LF  page 284 : A = VSENSE_PVCCIN_CPU1_DN ; B = GND

(kicad_pcb
	(version 20260206)
	(generator "pcbnew")
	(generator_version "10.0")
	(general
		(thickness 1.6)
		(legacy_teardrops no)
	)
	(paper "A4")
	(title_block
		(title "03242023_DA0F0TMBIJ0_F0T_Motherboard_J_brd_V01_OCP.brd")
		(comment 1 "Grand Teton / footprints 5394-5396 of 6105")
	)
	(layers
		(0 "F.Cu" signal "TOP")
		(4 "In1.Cu" signal "GND")
		(6 "In2.Cu" signal "IN1")
		(8 "In3.Cu" signal "GND1")
		(10 "In4.Cu" signal "IN2")
		(12 "In5.Cu" signal "GND2")
		(14 "In6.Cu" signal "IN3")
		(16 "In7.Cu" signal "GND3")
		(18 "In8.Cu" signal "VCC")
		(20 "In9.Cu" signal "VCC1")
		(22 "In10.Cu" signal "GND4")
		(24 "In11.Cu" signal "IN4")
		(26 "In12.Cu" signal "GND5")
		(28 "In13.Cu" signal "IN5")
		(30 "In14.Cu" signal "GND6")
		(32 "In15.Cu" signal "IN6")
		(34 "In16.Cu" signal "GND7")
		(2 "B.Cu" signal "BOTTOM")
		(9 "F.Adhes" user "F.Adhesive")
		(11 "B.Adhes" user "B.Adhesive")
		(13 "F.Paste" user "Package Geometry/Pastemask Top")
		(15 "B.Paste" user "Package Geometry/Pastemask Bottom")
		(5 "F.SilkS" user "Ref Des/Silkscreen Top")
		(7 "B.SilkS" user "Ref Des/Silkscreen Bottom")
		(1 "F.Mask" user "Board Geometry/Soldermask Top")
		(3 "B.Mask" user "Board Geometry/Soldermask Bottom")
		(17 "Dwgs.User" user "User.Drawings")
		(19 "Cmts.User" user "User.Comments")
		(21 "Eco1.User" user "User.Eco1")
		(23 "Eco2.User" user "User.Eco2")
		(25 "Edge.Cuts" user "Board Geometry/Outline")
		(27 "Margin" user)
		(31 "F.CrtYd" user "Package Geometry/Place Bound Top")
		(29 "B.CrtYd" user "Package Geometry/Place Bound Bottom")
		(35 "F.Fab" user "Ref Des/Assembly Top")
		(33 "B.Fab" user "Ref Des/Assembly Bottom")
	)
	(footprint ""
		(layer "B.Cu")
		(at 76.413106 -334.566514 -90)
		(property "Reference" "PR574"
			(at 0 0 90)
			(layer "B.SilkS")
			(hide yes)
			(effects
				(font
					(size 1.27 1.27)
				)
				(justify mirror)
			)
		)
		(property "Value" ""
			(at 0 0 90)
			(layer "B.Fab")
			(effects
				(font
					(size 1.27 1.27)
				)
				(justify mirror)
			)
		)
		(duplicate_pad_numbers_are_jumpers no)
		(fp_line
			(start -0.7874 0.4064)
			(end 0.7874 0.4064)
			(stroke
				(width 0.1524)
				(type default)
			)
			(layer "B.SilkS")
		)
		(fp_line
			(start 0.7874 0.4064)
			(end 0.7874 -0.4064)
			(stroke
				(width 0.1524)
				(type default)
			)
			(layer "B.SilkS")
		)
		(fp_line
			(start -0.7874 -0.4064)
			(end -0.7874 0.4064)
			(stroke
				(width 0.1524)
				(type default)
			)
			(layer "B.SilkS")
		)
		(fp_line
			(start 0.7874 -0.4064)
			(end -0.7874 -0.4064)
			(stroke
				(width 0.1524)
				(type default)
			)
			(layer "B.SilkS")
		)
		(fp_line
			(start -0.67945 0.3048)
			(end -0.120396 0.3048)
			(stroke
				(width 0.1)
				(type default)
			)
			(layer "B.Fab")
		)
		(fp_line
			(start -0.120396 0.3048)
			(end -0.120396 0.2794)
			(stroke
				(width 0.1)
				(type default)
			)
			(layer "B.Fab")
		)
		(fp_line
			(start 0.12065 0.3048)
			(end 0.67945 0.3048)
			(stroke
				(width 0.1)
				(type default)
			)
			(layer "B.Fab")
		)
		(fp_line
			(start 0.67945 0.3048)
			(end 0.67945 -0.305054)
			(stroke
				(width 0.1)
				(type default)
			)
			(layer "B.Fab")
		)
		(fp_line
			(start -0.120396 0.2794)
			(end 0.12065 0.2794)
			(stroke
				(width 0.1)
				(type default)
			)
			(layer "B.Fab")
		)
		(fp_line
			(start 0.12065 0.2794)
			(end 0.12065 0.3048)
			(stroke
				(width 0.1)
				(type default)
			)
			(layer "B.Fab")
		)
		(fp_line
			(start -0.12065 -0.2794)
			(end -0.12065 -0.3048)
			(stroke
				(width 0.1)
				(type default)
			)
			(layer "B.Fab")
		)
		(fp_line
			(start 0.12065 -0.2794)
			(end -0.12065 -0.2794)
			(stroke
				(width 0.1)
				(type default)
			)
			(layer "B.Fab")
		)
		(fp_line
			(start -0.67945 -0.3048)
			(end -0.67945 0.3048)
			(stroke
				(width 0.1)
				(type default)
			)
			(layer "B.Fab")
		)
		(fp_line
			(start -0.12065 -0.3048)
			(end -0.67945 -0.3048)
			(stroke
				(width 0.1)
				(type default)
			)
			(layer "B.Fab")
		)
		(fp_line
			(start 0.12065 -0.305054)
			(end 0.12065 -0.2794)
			(stroke
				(width 0.1)
				(type default)
			)
			(layer "B.Fab")
		)
		(fp_line
			(start 0.67945 -0.305054)
			(end 0.12065 -0.305054)
			(stroke
				(width 0.1)
				(type default)
			)
			(layer "B.Fab")
		)
		(pad "1" smd circle
			(at 0.40005 0 90)
			(size 0 0)
			(layers "B.Cu" "B.Mask" "B.Paste")
			(net "VSENSE_PVCCIN_CPU1_DN")
		)
		(pad "2" smd circle
			(at -0.40005 0 90)
			(size 0 0)
			(layers "B.Cu" "B.Mask" "B.Paste")
			(net "GND")
		)
	)
	(footprint ""
		(layer "B.Cu")
		(at 303.959768 -365.219488 180)
		(property "Reference" "PC1672"
			(at 0 0 0)
			(layer "B.SilkS")
			(hide yes)
			(effects
				(font
					(size 1.27 1.27)
				)
				(justify mirror)
			)
		)
		(property "Value" ""
			(at 0 0 0)
			(layer "B.Fab")
			(effects
				(font
					(size 1.27 1.27)
				)
				(justify mirror)
			)
		)
		(duplicate_pad_numbers_are_jumpers no)
		(fp_line
			(start 1.524 0.762)
			(end 1.524 -0.762)
			(stroke
				(width 0.1524)
				(type default)
			)
			(layer "B.SilkS")
		)
		(fp_line
			(start 1.524 -0.762)
			(end -1.524 -0.762)
			(stroke
				(width 0.1524)
				(type default)
			)
			(layer "B.SilkS")
		)
		(fp_line
			(start -1.524 0.762)
			(end 1.524 0.762)
			(stroke
				(width 0.1524)
				(type default)
			)
			(layer "B.SilkS")
		)
		(fp_line
			(start -1.524 -0.762)
			(end -1.524 0.762)
			(stroke
				(width 0.1524)
				(type default)
			)
			(layer "B.SilkS")
		)
		(fp_line
			(start 1.1049 0.724916)
			(end -1.1049 0.724916)
			(stroke
				(width 0.1)
				(type default)
			)
			(layer "B.Fab")
		)
		(fp_line
			(start 1.1049 -0.724916)
			(end 1.1049 0.724916)
			(stroke
				(width 0.1)
				(type default)
			)
			(layer "B.Fab")
		)
		(fp_line
			(start -1.1049 0.724916)
			(end -1.1049 -0.724916)
			(stroke
				(width 0.1)
				(type default)
			)
			(layer "B.Fab")
		)
		(fp_line
			(start -1.1049 -0.724916)
			(end 1.1049 -0.724916)
			(stroke
				(width 0.1)
				(type default)
			)
			(layer "B.Fab")
		)
		(pad "1" smd rect
			(at 0.889 0 180)
			(size 1.016 1.27)
			(layers "B.Cu" "B.Mask" "B.Paste")
			(net "SW_P12V_PVCCFA_EHV_FIVRA_CPU0_L")
		)
		(pad "2" smd rect
			(at -0.889 0 180)
			(size 1.016 1.27)
			(layers "B.Cu" "B.Mask" "B.Paste")
			(net "GND")
		)
	)
	(footprint ""
		(layer "B.Cu")
		(at 344.820748 -32.58439 180)
		(property "Reference" "R1962"
			(at 0 0 0)
			(layer "B.SilkS")
			(hide yes)
			(effects
				(font
					(size 1.27 1.27)
				)
				(justify mirror)
			)
		)
		(property "Value" ""
			(at 0 0 0)
			(layer "B.Fab")
			(effects
				(font
					(size 1.27 1.27)
				)
				(justify mirror)
			)
		)
		(duplicate_pad_numbers_are_jumpers no)
		(fp_line
			(start 0.7874 0.4064)
			(end 0.7874 -0.4064)
			(stroke
				(width 0.1524)
				(type default)
			)
			(layer "B.SilkS")
		)
		(fp_line
			(start 0.7874 -0.4064)
			(end -0.7874 -0.4064)
			(stroke
				(width 0.1524)
				(type default)
			)
			(layer "B.SilkS")
		)
		(fp_line
			(start -0.7874 0.4064)
			(end 0.7874 0.4064)
			(stroke
				(width 0.1524)
				(type default)
			)
			(layer "B.SilkS")
		)
		(fp_line
			(start -0.7874 -0.4064)
			(end -0.7874 0.4064)
			(stroke
				(width 0.1524)
				(type default)
			)
			(layer "B.SilkS")
		)
		(fp_line
			(start 0.67945 0.3048)
			(end 0.67945 -0.305054)
			(stroke
				(width 0.1)
				(type default)
			)
			(layer "B.Fab")
		)
		(fp_line
			(start 0.67945 -0.305054)
			(end 0.12065 -0.305054)
			(stroke
				(width 0.1)
				(type default)
			)
			(layer "B.Fab")
		)
		(fp_line
			(start 0.12065 0.3048)
			(end 0.67945 0.3048)
			(stroke
				(width 0.1)
				(type default)
			)
			(layer "B.Fab")
		)
		(fp_line
			(start 0.12065 0.2794)
			(end 0.12065 0.3048)
			(stroke
				(width 0.1)
				(type default)
			)
			(layer "B.Fab")
		)
		(fp_line
			(start 0.12065 -0.2794)
			(end -0.12065 -0.2794)
			(stroke
				(width 0.1)
				(type default)
			)
			(layer "B.Fab")
		)
		(fp_line
			(start 0.12065 -0.305054)
			(end 0.12065 -0.2794)
			(stroke
				(width 0.1)
				(type default)
			)
			(layer "B.Fab")
		)
		(fp_line
			(start -0.120396 0.3048)
			(end -0.120396 0.2794)
			(stroke
				(width 0.1)
				(type default)
			)
			(layer "B.Fab")
		)
		(fp_line
			(start -0.120396 0.2794)
			(end 0.12065 0.2794)
			(stroke
				(width 0.1)
				(type default)
			)
			(layer "B.Fab")
		)
		(fp_line
			(start -0.12065 -0.2794)
			(end -0.12065 -0.3048)
			(stroke
				(width 0.1)
				(type default)
			)
			(layer "B.Fab")
		)
		(fp_line
			(start -0.12065 -0.3048)
			(end -0.67945 -0.3048)
			(stroke
				(width 0.1)
				(type default)
			)
			(layer "B.Fab")
		)
		(fp_line
			(start -0.67945 0.3048)
			(end -0.120396 0.3048)
			(stroke
				(width 0.1)
				(type default)
			)
			(layer "B.Fab")
		)
		(fp_line
			(start -0.67945 -0.3048)
			(end -0.67945 0.3048)
			(stroke
				(width 0.1)
				(type default)
			)
			(layer "B.Fab")
		)
		(pad "1" smd circle
			(at 0.40005 0)
			(size 0 0)
			(layers "B.Cu" "B.Mask" "B.Paste")
			(net "FM_PCH_CONSENT_STRAP_N")
		)
		(pad "2" smd circle
			(at -0.40005 0)
			(size 0 0)
			(layers "B.Cu" "B.Mask" "B.Paste")
			(net "GND")
		)
	)
)
